# BASEBOARD_FAB2 (Tioga Pass) — schematic netlist excerpt (pin names and nets, part order shuffled) for the footprints in the layout excerpt that follows; sources: Cadence DE-HDL packaged netlist, KiCad conversion of Wiwynn_Tioga_Pass_MB.brd

C25W38  CAP_A  0.1UF 16V 10% X7R  pkg 0402V  page 149 : A = VCC_A_1V1 ; B = GND
R25W135  RES  4.75K 1% CHIP  pkg 0402  page 252 : A = P5V_VGA_D ; B = I2C_BMC_VGA_DDC_SDA_G
C3L6  CAPP  470UF 2.5V 20% ALUM  pkg 3018  page 220 : A = PVDDQ_DEF ; B = GND

(kicad_pcb
	(version 20260206)
	(generator "pcbnew")
	(generator_version "10.0")
	(general
		(thickness 1.6)
		(legacy_teardrops no)
	)
	(paper "A4")
	(title_block
		(title "Wiwynn_Tioga_Pass_MB.brd")
		(comment 1 "Tioga Pass / footprints 3981-3983 of 4770")
	)
	(layers
		(0 "F.Cu" signal "TOP")
		(4 "In1.Cu" signal "L2GND")
		(6 "In2.Cu" signal "L3")
		(8 "In3.Cu" signal "L4GND")
		(10 "In4.Cu" signal "L5")
		(12 "In5.Cu" signal "L6GND")
		(14 "In6.Cu" signal "L7VCC")
		(16 "In7.Cu" signal "L8VCC")
		(18 "In8.Cu" signal "L9GND")
		(20 "In9.Cu" signal "L10")
		(22 "In10.Cu" signal "L11GND")
		(24 "In11.Cu" signal "L12")
		(26 "In12.Cu" signal "L13GND")
		(2 "B.Cu" signal "BOTTOM")
		(9 "F.Adhes" user "F.Adhesive")
		(11 "B.Adhes" user "B.Adhesive")
		(13 "F.Paste" user "Package Geometry/Pastemask Top")
		(15 "B.Paste" user "Package Geometry/Pastemask Bottom")
		(5 "F.SilkS" user "Ref Des/Silkscreen Top")
		(7 "B.SilkS" user "Ref Des/Silkscreen Bottom")
		(1 "F.Mask" user "Board Geometry/Soldermask Top")
		(3 "B.Mask" user "Board Geometry/Soldermask Bottom")
		(17 "Dwgs.User" user "User.Drawings")
		(19 "Cmts.User" user "User.Comments")
		(21 "Eco1.User" user "User.Eco1")
		(23 "Eco2.User" user "User.Eco2")
		(25 "Edge.Cuts" user "Board Geometry/Outline")
		(27 "Margin" user)
		(31 "F.CrtYd" user "Package Geometry/Place Bound Top")
		(29 "B.CrtYd" user "Package Geometry/Place Bound Bottom")
		(35 "F.Fab" user "Ref Des/Assembly Top")
		(33 "B.Fab" user "Ref Des/Assembly Bottom")
	)
	(footprint ""
		(layer "B.Cu")
		(at 415.29 -31.0515 180)
		(property "Reference" "C25W38"
			(at 0.8382 -0.67818 180)
			(unlocked yes)
			(layer "B.SilkS")
			(effects
				(font
					(size 0.4064 0.254)
					(thickness 0.1524)
				)
				(justify left mirror)
			)
		)
		(property "Value" ""
			(at 0 0 0)
			(layer "B.Fab")
			(effects
				(font
					(size 1.27 1.27)
				)
				(justify mirror)
			)
		)
		(duplicate_pad_numbers_are_jumpers no)
		(fp_poly
			(pts
				(xy -0.3048 -0.1016) (xy -0.3048 0.9906) (xy 0.3048 0.9906) (xy 0.3048 -0.1016)
			)
			(stroke
				(width 0)
				(type default)
			)
			(fill no)
			(layer "B.CrtYd")
		)
		(fp_line
			(start 0.3048 0.9906)
			(end -0.3048 0.9906)
			(stroke
				(width 0.1)
				(type default)
			)
			(layer "B.Fab")
		)
		(fp_line
			(start 0.3048 -0.1016)
			(end 0.3048 0.9906)
			(stroke
				(width 0.1)
				(type default)
			)
			(layer "B.Fab")
		)
		(fp_line
			(start -0.3048 0.9906)
			(end -0.3048 -0.1016)
			(stroke
				(width 0.1)
				(type default)
			)
			(layer "B.Fab")
		)
		(fp_line
			(start -0.3048 -0.1016)
			(end 0.3048 -0.1016)
			(stroke
				(width 0.1)
				(type default)
			)
			(layer "B.Fab")
		)
		(pad "1" smd rect
			(at 0 0)
			(size 0.508 0.508)
			(layers "B.Cu" "B.Mask" "B.Paste")
			(net "VCC_A_1V1")
		)
		(pad "2" smd rect
			(at 0 0.889)
			(size 0.508 0.508)
			(layers "B.Cu" "B.Mask" "B.Paste")
			(net "GND")
		)
		(zone
			(layer "B.Cu")
			(hatch none 0.5)
			(connect_pads
				(clearance 0)
			)
			(min_thickness 0.25)
			(keepout
				(tracks not_allowed)
				(vias allowed)
				(pads allowed)
				(copperpour not_allowed)
				(footprints allowed)
			)
			(placement
				(enabled no)
				(sheetname "")
			)
			(fill
				(thermal_gap 0.5)
				(thermal_bridge_width 0.5)
				(island_removal_mode 0)
			)
			(polygon
				(pts
					(xy 415.036 -31.6865) (xy 415.544 -31.6865) (xy 415.544 -31.3055) (xy 415.036 -31.3055)
				)
			)
		)
		(zone
			(layer "B.Cu")
			(hatch none 0.5)
			(connect_pads
				(clearance 0)
			)
			(min_thickness 0.25)
			(keepout
				(tracks allowed)
				(vias not_allowed)
				(pads allowed)
				(copperpour not_allowed)
				(footprints allowed)
			)
			(placement
				(enabled no)
				(sheetname "")
			)
			(fill
				(thermal_gap 0.5)
				(thermal_bridge_width 0.5)
				(island_removal_mode 0)
			)
			(polygon
				(pts
					(xy 415.036 -31.3055) (xy 415.544 -31.3055) (xy 415.544 -31.6865) (xy 415.036 -31.6865)
				)
			)
		)
	)
	(footprint ""
		(layer "B.Cu")
		(at 334.01 -155.448 90)
		(property "Reference" "C3L6"
			(at -2.05867 9.144 0)
			(unlocked yes)
			(layer "B.SilkS")
			(effects
				(font
					(size 0.7874 0.5842)
					(thickness 0.1524)
				)
				(justify mirror)
			)
		)
		(property "Value" ""
			(at 0 0 90)
			(layer "B.Fab")
			(effects
				(font
					(size 1.27 1.27)
				)
				(justify mirror)
			)
		)
		(duplicate_pad_numbers_are_jumpers no)
		(fp_line
			(start 2.563114 -1.616456)
			(end 2.563114 1.633728)
			(stroke
				(width 0.1524)
				(type default)
			)
			(layer "B.SilkS")
		)
		(fp_line
			(start 1.6002 -1.616456)
			(end 2.563114 -1.616456)
			(stroke
				(width 0.1524)
				(type default)
			)
			(layer "B.SilkS")
		)
		(fp_line
			(start -1.6002 -1.616456)
			(end -2.504948 -1.616456)
			(stroke
				(width 0.1524)
				(type default)
			)
			(layer "B.SilkS")
		)
		(fp_line
			(start -2.504948 -1.616456)
			(end -2.504948 1.633728)
			(stroke
				(width 0.1524)
				(type default)
			)
			(layer "B.SilkS")
		)
		(fp_line
			(start 2.563114 1.633728)
			(end 1.6002 1.633728)
			(stroke
				(width 0.1524)
				(type default)
			)
			(layer "B.SilkS")
		)
		(fp_line
			(start -2.504948 1.633728)
			(end -1.6002 1.633728)
			(stroke
				(width 0.1524)
				(type default)
			)
			(layer "B.SilkS")
		)
		(fp_line
			(start 2.286 7.366)
			(end 2.286 1.632712)
			(stroke
				(width 0.1524)
				(type default)
			)
			(layer "B.SilkS")
		)
		(fp_line
			(start 2.286 7.366)
			(end 1.60147 7.366)
			(stroke
				(width 0.1524)
				(type default)
			)
			(layer "B.SilkS")
		)
		(fp_line
			(start -2.286 7.366)
			(end -2.286 1.63195)
			(stroke
				(width 0.1524)
				(type default)
			)
			(layer "B.SilkS")
		)
		(fp_line
			(start -2.286 7.366)
			(end -1.600708 7.366)
			(stroke
				(width 0.1524)
				(type default)
			)
			(layer "B.SilkS")
		)
		(fp_rect
			(start 2.286 7.366)
			(end -2.286 -0.254)
			(stroke
				(width 0)
				(type default)
			)
			(fill no)
			(layer "B.CrtYd")
		)
		(fp_line
			(start 2.286 -0.254)
			(end -2.286 -0.254)
			(stroke
				(width 0.1)
				(type default)
			)
			(layer "B.Fab")
		)
		(fp_line
			(start -2.286 -0.254)
			(end -2.286 7.366)
			(stroke
				(width 0.1)
				(type default)
			)
			(layer "B.Fab")
		)
		(fp_line
			(start 2.286 7.366)
			(end 2.286 -0.254)
			(stroke
				(width 0.1)
				(type default)
			)
			(layer "B.Fab")
		)
		(fp_line
			(start -2.286 7.366)
			(end 2.286 7.366)
			(stroke
				(width 0.1)
				(type default)
			)
			(layer "B.Fab")
		)
		(pad "1" smd rect
			(at 0 0 270)
			(size 2.54 3.048)
			(layers "B.Cu" "B.Mask" "B.Paste")
			(net "PVDDQ_DEF")
		)
		(pad "2" smd rect
			(at 0 7.112 270)
			(size 2.54 3.048)
			(layers "B.Cu" "B.Mask" "B.Paste")
			(net "GND")
		)
	)
	(footprint ""
		(layer "B.Cu")
		(at 496.523772 -46.198028 -90)
		(property "Reference" "R25W135"
			(at 0.8382 -0.67818 270)
			(unlocked yes)
			(layer "B.SilkS")
			(effects
				(font
					(size 0.4064 0.254)
					(thickness 0.1524)
				)
				(justify left mirror)
			)
		)
		(property "Value" ""
			(at 0 0 90)
			(layer "B.Fab")
			(effects
				(font
					(size 1.27 1.27)
				)
				(justify mirror)
			)
		)
		(duplicate_pad_numbers_are_jumpers no)
		(fp_poly
			(pts
				(xy 0.2794 -0.1016) (xy -0.2794 -0.1016) (xy -0.2794 0.9906) (xy 0.2794 0.9906)
			)
			(stroke
				(width 0)
				(type default)
			)
			(fill no)
			(layer "B.CrtYd")
		)
		(fp_line
			(start -0.2794 0.9906)
			(end -0.2794 -0.1016)
			(stroke
				(width 0.1)
				(type default)
			)
			(layer "B.Fab")
		)
		(fp_line
			(start 0.2794 0.9906)
			(end -0.2794 0.9906)
			(stroke
				(width 0.1)
				(type default)
			)
			(layer "B.Fab")
		)
		(fp_line
			(start -0.2794 -0.1016)
			(end 0.2794 -0.1016)
			(stroke
				(width 0.1)
				(type default)
			)
			(layer "B.Fab")
		)
		(fp_line
			(start 0.2794 -0.1016)
			(end 0.2794 0.9906)
			(stroke
				(width 0.1)
				(type default)
			)
			(layer "B.Fab")
		)
		(pad "1" smd rect
			(at 0 0 90)
			(size 0.508 0.508)
			(layers "B.Cu" "B.Mask" "B.Paste")
			(net "P5V_VGA_D")
		)
		(pad "2" smd rect
			(at 0 0.889 90)
			(size 0.508 0.508)
			(layers "B.Cu" "B.Mask" "B.Paste")
			(net "I2C_BMC_VGA_DDC_SDA_G")
		)
		(zone
			(layer "B.Cu")
			(hatch none 0.5)
			(connect_pads
				(clearance 0)
			)
			(min_thickness 0.25)
			(keepout
				(tracks not_allowed)
				(vias allowed)
				(pads allowed)
				(copperpour not_allowed)
				(footprints allowed)
			)
			(placement
				(enabled no)
				(sheetname "")
			)
			(fill
				(thermal_gap 0.5)
				(thermal_bridge_width 0.5)
				(island_removal_mode 0)
			)
			(polygon
				(pts
					(xy 495.888772 -45.944028) (xy 495.888772 -46.452028) (xy 496.269772 -46.452028) (xy 496.269772 -45.944028)
				)
			)
		)
		(zone
			(layer "B.Cu")
			(hatch none 0.5)
			(connect_pads
				(clearance 0)
			)
			(min_thickness 0.25)
			(keepout
				(tracks allowed)
				(vias not_allowed)
				(pads allowed)
				(copperpour not_allowed)
				(footprints allowed)
			)
			(placement
				(enabled no)
				(sheetname "")
			)
			(fill
				(thermal_gap 0.5)
				(thermal_bridge_width 0.5)
				(island_removal_mode 0)
			)
			(polygon
				(pts
					(xy 496.269772 -45.944028) (xy 496.269772 -46.452028) (xy 495.888772 -46.452028) (xy 495.888772 -45.944028)
				)
			)
		)
	)
)
